(kicad_pcb
	(version 20260206)
	(generator "pcbnew")
	(generator_version "10.0")
	(general
		(thickness 1.6)
		(legacy_teardrops no)
	)
	(paper "A4")
	(title_block
		(title "01162023_DA0F0TEBIF0_F0T_Expander_BD_F_brd_V02_OCP.brd")
		(comment 1 "Grand Teton / footprints 2434-2439 of 9728")
	)
	(layers
		(0 "F.Cu" signal "TOP")
		(4 "In1.Cu" signal "GND")
		(6 "In2.Cu" signal "VCC")
		(8 "In3.Cu" signal "VCC1")
		(10 "In4.Cu" signal "GND1")
		(12 "In5.Cu" signal "IN1")
		(14 "In6.Cu" signal "GND2")
		(16 "In7.Cu" signal "IN2")
		(18 "In8.Cu" signal "GND3")
		(20 "In9.Cu" signal "IN3")
		(22 "In10.Cu" signal "GND4")
		(24 "In11.Cu" signal "IN4")
		(26 "In12.Cu" signal "GND5")
		(28 "In13.Cu" signal "IN5")
		(30 "In14.Cu" signal "GND6")
		(32 "In15.Cu" signal "IN6")
		(34 "In16.Cu" signal "GND7")
		(2 "B.Cu" signal "BOTTOM")
		(9 "F.Adhes" user "F.Adhesive")
		(11 "B.Adhes" user "B.Adhesive")
		(13 "F.Paste" user "Package Geometry/Pastemask Top")
		(15 "B.Paste" user "Package Geometry/Pastemask Bottom")
		(5 "F.SilkS" user "Ref Des/Silkscreen Top")
		(7 "B.SilkS" user "Ref Des/Silkscreen Bottom")
		(1 "F.Mask" user "Board Geometry/Soldermask Top")
		(3 "B.Mask" user "Board Geometry/Soldermask Bottom")
		(17 "Dwgs.User" user "User.Drawings")
		(19 "Cmts.User" user "User.Comments")
		(21 "Eco1.User" user "User.Eco1")
		(23 "Eco2.User" user "User.Eco2")
		(25 "Edge.Cuts" user "Board Geometry/Outline")
		(27 "Margin" user)
		(31 "F.CrtYd" user "Package Geometry/Place Bound Top")
		(29 "B.CrtYd" user "Package Geometry/Place Bound Bottom")
		(35 "F.Fab" user "Ref Des/Assembly Top")
		(33 "B.Fab" user "Ref Des/Assembly Bottom")
	)
	(footprint ""
		(layer "F.Cu")
		(at 221.251272 -142.926562)
		(property "Reference" "R4210"
			(at 0 0 0)
			(layer "F.SilkS")
			(hide yes)
			(effects
				(font
					(size 1.27 1.27)
				)
			)
		)
		(property "Value" ""
			(at 0 0 0)
			(layer "F.Fab")
			(effects
				(font
					(size 1.27 1.27)
				)
			)
		)
		(duplicate_pad_numbers_are_jumpers no)
		(fp_line
			(start -0.7874 -0.4064)
			(end 0.7874 -0.4064)
			(stroke
				(width 0.1524)
				(type default)
			)
			(layer "F.SilkS")
		)
		(fp_line
			(start -0.7874 0.4064)
			(end -0.7874 -0.4064)
			(stroke
				(width 0.1524)
				(type default)
			)
			(layer "F.SilkS")
		)
		(fp_line
			(start 0.7874 -0.4064)
			(end 0.7874 0.4064)
			(stroke
				(width 0.1524)
				(type default)
			)
			(layer "F.SilkS")
		)
		(fp_line
			(start 0.7874 0.4064)
			(end -0.7874 0.4064)
			(stroke
				(width 0.1524)
				(type default)
			)
			(layer "F.SilkS")
		)
		(fp_line
			(start -0.67945 -0.305054)
			(end -0.12065 -0.305054)
			(stroke
				(width 0.1)
				(type default)
			)
			(layer "F.Fab")
		)
		(fp_line
			(start -0.67945 0.3048)
			(end -0.67945 -0.305054)
			(stroke
				(width 0.1)
				(type default)
			)
			(layer "F.Fab")
		)
		(fp_line
			(start -0.12065 -0.305054)
			(end -0.12065 -0.2794)
			(stroke
				(width 0.1)
				(type default)
			)
			(layer "F.Fab")
		)
		(fp_line
			(start -0.12065 -0.2794)
			(end 0.12065 -0.2794)
			(stroke
				(width 0.1)
				(type default)
			)
			(layer "F.Fab")
		)
		(fp_line
			(start -0.12065 0.2794)
			(end -0.12065 0.3048)
			(stroke
				(width 0.1)
				(type default)
			)
			(layer "F.Fab")
		)
		(fp_line
			(start -0.12065 0.3048)
			(end -0.67945 0.3048)
			(stroke
				(width 0.1)
				(type default)
			)
			(layer "F.Fab")
		)
		(fp_line
			(start 0.120396 0.2794)
			(end -0.12065 0.2794)
			(stroke
				(width 0.1)
				(type default)
			)
			(layer "F.Fab")
		)
		(fp_line
			(start 0.120396 0.3048)
			(end 0.120396 0.2794)
			(stroke
				(width 0.1)
				(type default)
			)
			(layer "F.Fab")
		)
		(fp_line
			(start 0.12065 -0.3048)
			(end 0.67945 -0.3048)
			(stroke
				(width 0.1)
				(type default)
			)
			(layer "F.Fab")
		)
		(fp_line
			(start 0.12065 -0.2794)
			(end 0.12065 -0.3048)
			(stroke
				(width 0.1)
				(type default)
			)
			(layer "F.Fab")
		)
		(fp_line
			(start 0.67945 -0.3048)
			(end 0.67945 0.3048)
			(stroke
				(width 0.1)
				(type default)
			)
			(layer "F.Fab")
		)
		(fp_line
			(start 0.67945 0.3048)
			(end 0.120396 0.3048)
			(stroke
				(width 0.1)
				(type default)
			)
			(layer "F.Fab")
		)
		(pad "1" smd circle
			(at -0.40005 0)
			(size 0 0)
			(layers "F.Cu" "F.Mask" "F.Paste")
			(net "GND")
		)
		(pad "2" smd circle
			(at 0.40005 0)
			(size 0 0)
			(layers "F.Cu" "F.Mask" "F.Paste")
			(net "FM_CK440_PEX_DEV_25M_EN")
		)
	)
	(footprint ""
		(layer "F.Cu")
		(at 150.394162 -241.610134 90)
		(property "Reference" "R6574"
			(at 0 0 90)
			(layer "F.SilkS")
			(hide yes)
			(effects
				(font
					(size 1.27 1.27)
				)
			)
		)
		(property "Value" ""
			(at 0 0 90)
			(layer "F.Fab")
			(effects
				(font
					(size 1.27 1.27)
				)
			)
		)
		(duplicate_pad_numbers_are_jumpers no)
		(fp_line
			(start 0.7874 -0.4064)
			(end 0.7874 0.4064)
			(stroke
				(width 0.1524)
				(type default)
			)
			(layer "F.SilkS")
		)
		(fp_line
			(start -0.7874 -0.4064)
			(end 0.7874 -0.4064)
			(stroke
				(width 0.1524)
				(type default)
			)
			(layer "F.SilkS")
		)
		(fp_line
			(start 0.7874 0.4064)
			(end -0.7874 0.4064)
			(stroke
				(width 0.1524)
				(type default)
			)
			(layer "F.SilkS")
		)
		(fp_line
			(start -0.7874 0.4064)
			(end -0.7874 -0.4064)
			(stroke
				(width 0.1524)
				(type default)
			)
			(layer "F.SilkS")
		)
		(fp_line
			(start -0.12065 -0.305054)
			(end -0.12065 -0.2794)
			(stroke
				(width 0.1)
				(type default)
			)
			(layer "F.Fab")
		)
		(fp_line
			(start -0.67945 -0.305054)
			(end -0.12065 -0.305054)
			(stroke
				(width 0.1)
				(type default)
			)
			(layer "F.Fab")
		)
		(fp_line
			(start 0.67945 -0.3048)
			(end 0.67945 0.3048)
			(stroke
				(width 0.1)
				(type default)
			)
			(layer "F.Fab")
		)
		(fp_line
			(start 0.12065 -0.3048)
			(end 0.67945 -0.3048)
			(stroke
				(width 0.1)
				(type default)
			)
			(layer "F.Fab")
		)
		(fp_line
			(start 0.12065 -0.2794)
			(end 0.12065 -0.3048)
			(stroke
				(width 0.1)
				(type default)
			)
			(layer "F.Fab")
		)
		(fp_line
			(start -0.12065 -0.2794)
			(end 0.12065 -0.2794)
			(stroke
				(width 0.1)
				(type default)
			)
			(layer "F.Fab")
		)
		(fp_line
			(start 0.120396 0.2794)
			(end -0.12065 0.2794)
			(stroke
				(width 0.1)
				(type default)
			)
			(layer "F.Fab")
		)
		(fp_line
			(start -0.12065 0.2794)
			(end -0.12065 0.3048)
			(stroke
				(width 0.1)
				(type default)
			)
			(layer "F.Fab")
		)
		(fp_line
			(start 0.67945 0.3048)
			(end 0.120396 0.3048)
			(stroke
				(width 0.1)
				(type default)
			)
			(layer "F.Fab")
		)
		(fp_line
			(start 0.120396 0.3048)
			(end 0.120396 0.2794)
			(stroke
				(width 0.1)
				(type default)
			)
			(layer "F.Fab")
		)
		(fp_line
			(start -0.12065 0.3048)
			(end -0.67945 0.3048)
			(stroke
				(width 0.1)
				(type default)
			)
			(layer "F.Fab")
		)
		(fp_line
			(start -0.67945 0.3048)
			(end -0.67945 -0.305054)
			(stroke
				(width 0.1)
				(type default)
			)
			(layer "F.Fab")
		)
		(pad "1" smd circle
			(at -0.40005 0 90)
			(size 0 0)
			(layers "F.Cu" "F.Mask" "F.Paste")
			(net "P1V8_PLL_PEX1_ADJ")
		)
		(pad "2" smd circle
			(at 0.40005 0 90)
			(size 0 0)
			(layers "F.Cu" "F.Mask" "F.Paste")
			(net "GND")
		)
	)
	(footprint ""
		(layer "F.Cu")
		(at 83.109562 -343.952322 90)
		(property "Reference" "C107"
			(at 0 0 90)
			(layer "F.SilkS")
			(hide yes)
			(effects
				(font
					(size 1.27 1.27)
				)
			)
		)
		(property "Value" ""
			(at 0 0 90)
			(layer "F.Fab")
			(effects
				(font
					(size 1.27 1.27)
				)
			)
		)
		(duplicate_pad_numbers_are_jumpers no)
		(fp_line
			(start 0.299974 -0.150114)
			(end 0.299974 0.150114)
			(stroke
				(width 0.1)
				(type default)
			)
			(layer "F.Fab")
		)
		(fp_line
			(start -0.299974 -0.150114)
			(end 0.299974 -0.150114)
			(stroke
				(width 0.1)
				(type default)
			)
			(layer "F.Fab")
		)
		(fp_line
			(start 0.299974 0.150114)
			(end -0.299974 0.150114)
			(stroke
				(width 0.1)
				(type default)
			)
			(layer "F.Fab")
		)
		(fp_line
			(start -0.299974 0.150114)
			(end -0.299974 -0.150114)
			(stroke
				(width 0.1)
				(type default)
			)
			(layer "F.Fab")
		)
		(pad "1" smd rect
			(at -0.2667 0 90)
			(size 0.3048 0.381)
			(layers "F.Cu" "F.Mask" "F.Paste")
			(net "P5E_PEX0_STN5_TX_DP<90>")
		)
		(pad "2" smd rect
			(at 0.2667 0 90)
			(size 0.3048 0.381)
			(layers "F.Cu" "F.Mask" "F.Paste")
			(net "P5E_PEX0_STN5_TX_C_DP<90>")
		)
	)
	(footprint ""
		(layer "F.Cu")
		(at 161.626804 -55.418228 90)
		(property "Reference" "PC370"
			(at 0 0 90)
			(layer "F.SilkS")
			(hide yes)
			(effects
				(font
					(size 1.27 1.27)
				)
			)
		)
		(property "Value" ""
			(at 0 0 90)
			(layer "F.Fab")
			(effects
				(font
					(size 1.27 1.27)
				)
			)
		)
		(duplicate_pad_numbers_are_jumpers no)
		(fp_line
			(start 0.7874 -0.4064)
			(end 0.7874 0.4064)
			(stroke
				(width 0.1524)
				(type default)
			)
			(layer "F.SilkS")
		)
		(fp_line
			(start -0.7874 -0.4064)
			(end 0.7874 -0.4064)
			(stroke
				(width 0.1524)
				(type default)
			)
			(layer "F.SilkS")
		)
		(fp_line
			(start 0.7874 0.4064)
			(end -0.7874 0.4064)
			(stroke
				(width 0.1524)
				(type default)
			)
			(layer "F.SilkS")
		)
		(fp_line
			(start -0.7874 0.4064)
			(end -0.7874 -0.4064)
			(stroke
				(width 0.1524)
				(type default)
			)
			(layer "F.SilkS")
		)
		(fp_line
			(start -0.12065 -0.305054)
			(end -0.12065 -0.2794)
			(stroke
				(width 0.1)
				(type default)
			)
			(layer "F.Fab")
		)
		(fp_line
			(start -0.67945 -0.305054)
			(end -0.12065 -0.305054)
			(stroke
				(width 0.1)
				(type default)
			)
			(layer "F.Fab")
		)
		(fp_line
			(start 0.67945 -0.3048)
			(end 0.67945 0.3048)
			(stroke
				(width 0.1)
				(type default)
			)
			(layer "F.Fab")
		)
		(fp_line
			(start 0.12065 -0.3048)
			(end 0.67945 -0.3048)
			(stroke
				(width 0.1)
				(type default)
			)
			(layer "F.Fab")
		)
		(fp_line
			(start 0.12065 -0.2794)
			(end 0.12065 -0.3048)
			(stroke
				(width 0.1)
				(type default)
			)
			(layer "F.Fab")
		)
		(fp_line
			(start -0.12065 -0.2794)
			(end 0.12065 -0.2794)
			(stroke
				(width 0.1)
				(type default)
			)
			(layer "F.Fab")
		)
		(fp_line
			(start 0.120396 0.2794)
			(end -0.12065 0.2794)
			(stroke
				(width 0.1)
				(type default)
			)
			(layer "F.Fab")
		)
		(fp_line
			(start -0.12065 0.2794)
			(end -0.12065 0.3048)
			(stroke
				(width 0.1)
				(type default)
			)
			(layer "F.Fab")
		)
		(fp_line
			(start 0.67945 0.3048)
			(end 0.120396 0.3048)
			(stroke
				(width 0.1)
				(type default)
			)
			(layer "F.Fab")
		)
		(fp_line
			(start 0.120396 0.3048)
			(end 0.120396 0.2794)
			(stroke
				(width 0.1)
				(type default)
			)
			(layer "F.Fab")
		)
		(fp_line
			(start -0.12065 0.3048)
			(end -0.67945 0.3048)
			(stroke
				(width 0.1)
				(type default)
			)
			(layer "F.Fab")
		)
		(fp_line
			(start -0.67945 0.3048)
			(end -0.67945 -0.305054)
			(stroke
				(width 0.1)
				(type default)
			)
			(layer "F.Fab")
		)
		(pad "1" smd circle
			(at -0.40005 0 90)
			(size 0 0)
			(layers "F.Cu" "F.Mask" "F.Paste")
			(net "P12V_SSD5_R")
		)
		(pad "2" smd circle
			(at 0.40005 0 90)
			(size 0 0)
			(layers "F.Cu" "F.Mask" "F.Paste")
			(net "GND")
		)
	)
	(footprint ""
		(layer "F.Cu")
		(at 253.587504 -201.87793 90)
		(property "Reference" "U294"
			(at -1.692656 3.454146 90)
			(unlocked yes)
			(layer "F.SilkS")
			(effects
				(font
					(size 0.7874 0.5842)
					(thickness 0.1524)
				)
				(justify left)
			)
		)
		(property "Value" ""
			(at 0 0 90)
			(layer "F.Fab")
			(effects
				(font
					(size 1.27 1.27)
				)
			)
		)
		(duplicate_pad_numbers_are_jumpers no)
		(fp_line
			(start 2.0066 -2.5527)
			(end 2.0066 2.5527)
			(stroke
				(width 0.1524)
				(type default)
			)
			(layer "F.SilkS")
		)
		(fp_line
			(start 0.5715 -2.5527)
			(end 2.0066 -2.5527)
			(stroke
				(width 0.1524)
				(type default)
			)
			(layer "F.SilkS")
		)
		(fp_line
			(start -0.5715 -2.5527)
			(end 0 -1.9812)
			(stroke
				(width 0.1524)
				(type default)
			)
			(layer "F.SilkS")
		)
		(fp_line
			(start -2.0066 -2.5527)
			(end -0.5715 -2.5527)
			(stroke
				(width 0.1524)
				(type default)
			)
			(layer "F.SilkS")
		)
		(fp_line
			(start 0 -1.9812)
			(end 0.5715 -2.5527)
			(stroke
				(width 0.1524)
				(type default)
			)
			(layer "F.SilkS")
		)
		(fp_line
			(start 2.0066 2.5527)
			(end -2.0066 2.5527)
			(stroke
				(width 0.1524)
				(type default)
			)
			(layer "F.SilkS")
		)
		(fp_line
			(start -2.0066 2.5527)
			(end -2.0066 -2.5527)
			(stroke
				(width 0.1524)
				(type default)
			)
			(layer "F.SilkS")
		)
		(fp_poly
			(pts
				(xy -4.90982 -1.712214) (xy -4.90982 -2.337054) (xy -4.3561 -2.008886)
			)
			(stroke
				(width 0)
				(type default)
			)
			(fill yes)
			(layer "F.SilkS")
		)
		(fp_line
			(start 2.249932 -2.549906)
			(end 2.249932 2.549906)
			(stroke
				(width 0.1)
				(type default)
			)
			(layer "F.Fab")
		)
		(fp_line
			(start -2.249932 -2.549906)
			(end 2.249932 -2.549906)
			(stroke
				(width 0.1)
				(type default)
			)
			(layer "F.Fab")
		)
		(fp_line
			(start 2.249932 2.549906)
			(end -2.249932 2.549906)
			(stroke
				(width 0.1)
				(type default)
			)
			(layer "F.Fab")
		)
		(fp_line
			(start -2.249932 2.549906)
			(end -2.249932 -2.549906)
			(stroke
				(width 0.1)
				(type default)
			)
			(layer "F.Fab")
		)
		(fp_poly
			(pts
				(xy -4.36372 -1.608328) (xy -4.36372 -2.233168) (xy -3.81 -1.905)
			)
			(stroke
				(width 0)
				(type default)
			)
			(fill yes)
			(layer "F.Fab")
		)
		(pad "1" smd rect
			(at -2.921 -1.949958)
			(size 0.3556 1.4986)
			(layers "F.Cu" "F.Mask" "F.Paste")
			(net "JTAG_BIC_EN_R")
		)
		(pad "2" smd rect
			(at -2.921 -1.299972)
			(size 0.3556 1.4986)
			(layers "F.Cu" "F.Mask" "F.Paste")
			(net "JTAG_BIC_TCK_R1")
		)
		(pad "3" smd rect
			(at -2.921 -0.649986)
			(size 0.3556 1.4986)
			(layers "F.Cu" "F.Mask" "F.Paste")
			(net "JTAG_PLD_TCK")
		)
		(pad "4" smd rect
			(at -2.921 0)
			(size 0.3556 1.4986)
			(layers "F.Cu" "F.Mask" "F.Paste")
			(net "JTAG_BIC_EN_R")
		)
		(pad "5" smd rect
			(at -2.921 0.649986)
			(size 0.3556 1.4986)
			(layers "F.Cu" "F.Mask" "F.Paste")
			(net "JTAG_BIC_TMS_R1")
		)
		(pad "6" smd rect
			(at -2.921 1.299972)
			(size 0.3556 1.4986)
			(layers "F.Cu" "F.Mask" "F.Paste")
			(net "JTAG_PLD_TMS")
		)
		(pad "7" smd rect
			(at -2.921 1.949958)
			(size 0.3556 1.4986)
			(layers "F.Cu" "F.Mask" "F.Paste")
			(net "GND")
		)
		(pad "8" smd rect
			(at 2.921 1.949958)
			(size 0.3556 1.4986)
			(layers "F.Cu" "F.Mask" "F.Paste")
			(net "JTAG_PLD_TDI")
		)
		(pad "9" smd rect
			(at 2.921 1.299972)
			(size 0.3556 1.4986)
			(layers "F.Cu" "F.Mask" "F.Paste")
			(net "JTAG_BIC_TDI_R1")
		)
		(pad "10" smd rect
			(at 2.921 0.649986)
			(size 0.3556 1.4986)
			(layers "F.Cu" "F.Mask" "F.Paste")
			(net "JTAG_BIC_EN_R")
		)
		(pad "11" smd rect
			(at 2.921 0)
			(size 0.3556 1.4986)
			(layers "F.Cu" "F.Mask" "F.Paste")
			(net "JTAG_PLD_TDO")
		)
		(pad "12" smd rect
			(at 2.921 -0.649986)
			(size 0.3556 1.4986)
			(layers "F.Cu" "F.Mask" "F.Paste")
			(net "JTAG_BIC_TDO")
		)
		(pad "13" smd rect
			(at 2.921 -1.299972)
			(size 0.3556 1.4986)
			(layers "F.Cu" "F.Mask" "F.Paste")
			(net "JTAG_BIC_EN_R")
		)
		(pad "14" smd rect
			(at 2.921 -1.949958)
			(size 0.3556 1.4986)
			(layers "F.Cu" "F.Mask" "F.Paste")
			(net "P3V3_AUX")
		)
	)
	(footprint ""
		(layer "F.Cu")
		(at 305.147218 -19.33956)
		(property "Reference" "C3944"
			(at 0 0 0)
			(layer "F.SilkS")
			(hide yes)
			(effects
				(font
					(size 1.27 1.27)
				)
			)
		)
		(property "Value" ""
			(at 0 0 0)
			(layer "F.Fab")
			(effects
				(font
					(size 1.27 1.27)
				)
			)
		)
		(duplicate_pad_numbers_are_jumpers no)
		(fp_line
			(start -0.7874 -0.4064)
			(end 0.7874 -0.4064)
			(stroke
				(width 0.1524)
				(type default)
			)
			(layer "F.SilkS")
		)
		(fp_line
			(start -0.7874 0.4064)
			(end -0.7874 -0.4064)
			(stroke
				(width 0.1524)
				(type default)
			)
			(layer "F.SilkS")
		)
		(fp_line
			(start 0.7874 -0.4064)
			(end 0.7874 0.4064)
			(stroke
				(width 0.1524)
				(type default)
			)
			(layer "F.SilkS")
		)
		(fp_line
			(start 0.7874 0.4064)
			(end -0.7874 0.4064)
			(stroke
				(width 0.1524)
				(type default)
			)
			(layer "F.SilkS")
		)
		(fp_line
			(start -0.67945 -0.305054)
			(end -0.12065 -0.305054)
			(stroke
				(width 0.1)
				(type default)
			)
			(layer "F.Fab")
		)
		(fp_line
			(start -0.67945 0.3048)
			(end -0.67945 -0.305054)
			(stroke
				(width 0.1)
				(type default)
			)
			(layer "F.Fab")
		)
		(fp_line
			(start -0.12065 -0.305054)
			(end -0.12065 -0.2794)
			(stroke
				(width 0.1)
				(type default)
			)
			(layer "F.Fab")
		)
		(fp_line
			(start -0.12065 -0.2794)
			(end 0.12065 -0.2794)
			(stroke
				(width 0.1)
				(type default)
			)
			(layer "F.Fab")
		)
		(fp_line
			(start -0.12065 0.2794)
			(end -0.12065 0.3048)
			(stroke
				(width 0.1)
				(type default)
			)
			(layer "F.Fab")
		)
		(fp_line
			(start -0.12065 0.3048)
			(end -0.67945 0.3048)
			(stroke
				(width 0.1)
				(type default)
			)
			(layer "F.Fab")
		)
		(fp_line
			(start 0.120396 0.2794)
			(end -0.12065 0.2794)
			(stroke
				(width 0.1)
				(type default)
			)
			(layer "F.Fab")
		)
		(fp_line
			(start 0.120396 0.3048)
			(end 0.120396 0.2794)
			(stroke
				(width 0.1)
				(type default)
			)
			(layer "F.Fab")
		)
		(fp_line
			(start 0.12065 -0.3048)
			(end 0.67945 -0.3048)
			(stroke
				(width 0.1)
				(type default)
			)
			(layer "F.Fab")
		)
		(fp_line
			(start 0.12065 -0.2794)
			(end 0.12065 -0.3048)
			(stroke
				(width 0.1)
				(type default)
			)
			(layer "F.Fab")
		)
		(fp_line
			(start 0.67945 -0.3048)
			(end 0.67945 0.3048)
			(stroke
				(width 0.1)
				(type default)
			)
			(layer "F.Fab")
		)
		(fp_line
			(start 0.67945 0.3048)
			(end 0.120396 0.3048)
			(stroke
				(width 0.1)
				(type default)
			)
			(layer "F.Fab")
		)
		(pad "1" smd circle
			(at -0.40005 0)
			(size 0 0)
			(layers "F.Cu" "F.Mask" "F.Paste")
			(net "P12V_SSD10")
		)
		(pad "2" smd circle
			(at 0.40005 0)
			(size 0 0)
			(layers "F.Cu" "F.Mask" "F.Paste")
			(net "GND")
		)
	)
)
